FILE_TYPE = CONNECTIVITY;
{Allegro Design Entry HDL 16.6-p007 (v16-6-112F) 10/10/2012}
"PAGE_NUMBER" = 181;
0"NC";
1"P3E_CPU1_PE3_MP_TXP<7:0>";
2"P3E_CPU1_PE3_MP_TXN<7:0>";
3"P3E_CPU1_PE3_MP_RXN<7:0>";
4"P3E_CPU1_PE3_MP_RXP<7:0>";
5"GND\g";
6"P3V3_STBY\g";
7"GND\g";
8"P12V_PSU\g";
9"GND\g";
10"P3V3_STBY\g";
11"GND\g";
12"GND\g";
13"GND\g";
14"GND\g";
15"GND\g";
16"P12V_PSU\g";
17"P3V3_STBY\g";
18"SMB_BMC_PMBUS_STBY_LVC3_SDA";
19"SMB_BMC_PMBUS_STBY_LVC3_SCL";
20"FM_MATED_IN_N";
21"FM_MP_PS_FAIL_N";
22"IRQ_SML1_PMBUS_ALERT_R_N";
23"FM_MATED_IN_N";
24"FM_MB_SLOT_ID1";
25"FAN_TACH0_R";
26"FAN_TACH2_R";
27"FAN_TACH3_R";
28"FAN_TACH1_R";
29"FM_MATED_IN_D1_N";
30"FM_MATED_IN_D2_N";
31"FM_P12V_HOTSWAP0_EN";
32"P3E_CPU1_PE3_MP_C_TXP<2>";
33"P3E_CPU1_PE3_MP_C_TXN<2>";
34"FAN_PWM_OUT_SYS0_R1";
35"FM_PS_EN";
36"NIC_MDI_MNG_TX_DP";
37"NIC_MDI_MNG_TX_DN";
38"NIC_MDI_MNG_RX_DP";
39"P3E_CPU1_PE3_MP_RXP<0>";
40"P3E_CPU1_PE3_MP_RXN<1>";
41"P3E_CPU1_PE3_MP_RXP<2>";
42"P3E_CPU1_PE3_MP_RXN<2>";
43"SP2_BMC_CM_UART_TX_R1";
44"P3E_CPU1_PE3_MP_RXN<5>";
45"P3E_CPU1_PE3_MP_TXP<2>";
46"P3E_CPU1_PE3_MP_RXN<7>";
47"FM_ENABLE_FAN_POWER";
48"SPA_MID_DBG_TX_R";
49"P3E_CPU1_PE3_MP_RXP<7>";
50"P3E_CPU1_PE3_MP_RXN<6>";
51"P3E_CPU1_PE3_MP_RXP<6>";
52"P3E_CPU1_PE3_MP_RXN<3>";
53"CLK_100M_AIRMAX8_PE1_DN";
54"FAN_PWM_OUT_SYS0_R";
55"FAN_TACH1";
56"FAN_TACH0";
57"SPA_MID_DBG_RX_R";
58"SPA_MID_DBG_TX";
59"SP2_BMC_CM_UART_RX_R1";
60"FAN_TACH2";
61"FM_CTNR_PS_ON_R";
62"FM_MP_PS_REDUNDANT_LOST_N";
63"FM_MB_SLOT_ID2";
64"SPA_MID_DBG_RX";
65"FM_MB_SLOT_ID0";
66"FAN_TACH3";
67"P3E_CPU1_PE3_MP_TXN<4>";
68"P3E_CPU1_PE3_MP_TXP<5>";
69"P3E_CPU1_PE3_MP_TXN<2>";
70"P3E_CPU1_PE3_MP_TXN<1>";
71"P3E_CPU1_PE3_MP_TXP<4>";
72"P3E_CPU1_PE3_MP_TXN<5>";
73"P3E_CPU1_PE3_MP_TXP<0>";
74"P3E_CPU1_PE3_MP_TXP<1>";
75"CLK_100M_AIRMAX8_PE1_DP";
76"FM_MATED_IN_N";
77"P3E_CPU1_PE3_MP_RXP<4>";
78"P3E_CPU1_PE3_MP_RXP<5>";
79"P3E_CPU1_PE3_MP_RXP<1>";
80"P3E_CPU1_PE3_MP_RXN<0>";
81"P3E_CPU1_PE3_MP_C_TXN<1>";
82"P3E_CPU1_PE3_MP_C_TXN<5>";
83"P3E_CPU1_PE3_MP_C_TXN<4>";
84"P3E_CPU1_PE3_MP_C_TXP<6>";
85"RST_PCIE_MIDPLANE_N";
86"P3E_CPU1_PE3_MP_C_TXP<0>";
87"P3E_CPU1_PE3_MP_C_TXN<7>";
88"FM_MB_SLOT_ID2";
89"FM_MB_SLOT_ID1";
90"FM_MB_SLOT_ID0";
91"NIC_MDI_MNG_RX_DN";
92"P3E_CPU1_PE3_MP_C_TXP<5>";
93"P3E_CPU1_PE3_MP_C_TXN<0>";
94"P3E_CPU1_PE3_MP_C_TXP<1>";
95"P3E_CPU1_PE3_MP_TXN<0>";
96"P3E_CPU1_PE3_MP_C_TXP<4>";
97"P3E_CPU1_PE3_MP_C_TXP<3>";
98"P3E_CPU1_PE3_MP_RXP<3>";
99"P3E_CPU1_PE3_MP_RXN<4>";
100"P3E_CPU1_PE3_MP_TXN<3>";
101"P3E_CPU1_PE3_MP_TXN<7>";
102"P3E_CPU1_PE3_MP_TXP<7>";
103"P3E_CPU1_PE3_MP_TXN<6>";
104"P3E_CPU1_PE3_MP_TXP<6>";
105"PWRGD_P12V_HSC_DLY";
106"FM_CTNR_PS_ON";
107"P3E_CPU1_PE3_MP_TXP<3>";
108"P3E_CPU1_PE3_MP_C_TXN<3>";
109"P3E_CPU1_PE3_MP_C_TXP<7>";
110"P3E_CPU1_PE3_MP_C_TXN<6>";
111"SMB_BMC_PMBUS_STBY_LVC3_SCL";
112"SMB_BMC_PMBUS_STBY_LVC3_SDA";
113"IRQ_SML1_PMBUS_ALERT_R_N";
%"GND"
"1","(3650,800)","0","mstr_symbols","I104";
;
BOM_COST"NT_BASE_VRD"
ROOM"P2V5_LAN_AUX_VR"
CDS_LIB"mstr_symbols"
VOLTAGE"0"
SIZE"1B"
BODY_TYPE"PLUMBING"
HDL_POWER"GND";
"A\NAC"5;
%"P3V3_STBY"
"1","(3650,1600)","0","mstr_symbols","I105";
;
CDS_LIB"mstr_symbols"
VOLTAGE"3.3V"
SIZE"1B"
BODY_TYPE"PLUMBING"
HDL_POWER"P3V3_STBY";
"G\NAC"6;
%"CONN8_H62179001"
"1","(4100,1250)","0","mstr_conn","I106";
;
MATERIAL"CONN"
LOCATION"J1F3"
POP"NOPOP"
PART_NUMBER"H62179-001"
CDS_LIB"mstr_conn"
CDS_SEC"1"
$SEC"1"
CDS_LOCATION"J1F3"
ROOM"IO_SLOT"
PACK_TYPE"PIP";
"IO1"
$PN"1"6;
"IO3"
$PN"3"21;
"IO2"
$PN"2"62;
"IO4"
$PN"4"23;
"IO6"
$PN"6"18;
"IO5"
$PN"5"22;
"IO8"
$PN"8"5;
"IO7"
$PN"7"19;
%"TAP"
"6","(3175,2750)","2","mstr_standard","I107";
;
CDS_LIB"mstr_standard"
BODY_TYPE"PLUMBING"
HDL_TAP"TRUE";
"B \NAC \NWC"2;
"S \NAC"
BN"1"70;
%"TAP"
"6","(3175,2600)","2","mstr_standard","I108";
;
CDS_LIB"mstr_standard"
BODY_TYPE"PLUMBING"
HDL_TAP"TRUE";
"B \NAC \NWC"2;
"S \NAC"
BN"2"69;
%"TAP"
"6","(3175,2900)","2","mstr_standard","I112";
;
CDS_LIB"mstr_standard"
BODY_TYPE"PLUMBING"
HDL_TAP"TRUE";
"B \NAC \NWC"2;
"S \NAC"
BN"0"95;
%"TAP"
"6","(3175,3100)","2","mstr_standard","I113";
;
CDS_LIB"mstr_standard"
BODY_TYPE"PLUMBING"
HDL_TAP"TRUE";
"B \NAC \NWC"2;
"S \NAC"
BN"5"72;
%"TAP"
"6","(3175,3300)","2","mstr_standard","I114";
;
CDS_LIB"mstr_standard"
BODY_TYPE"PLUMBING"
HDL_TAP"TRUE";
"B \NAC \NWC"2;
"S \NAC"
BN"4"67;
%"TAP"
"6","(3175,3450)","2","mstr_standard","I115";
;
CDS_LIB"mstr_standard"
BODY_TYPE"PLUMBING"
HDL_TAP"TRUE";
"B \NAC \NWC"2;
"S \NAC"
BN"3"100;
%"TAP"
"6","(3175,3600)","2","mstr_standard","I116";
;
CDS_LIB"mstr_standard"
BODY_TYPE"PLUMBING"
HDL_TAP"TRUE";
"B \NAC \NWC"2;
"S \NAC"
BN"7"101;
%"TAP"
"6","(3175,3800)","2","mstr_standard","I117";
;
CDS_LIB"mstr_standard"
BODY_TYPE"PLUMBING"
HDL_TAP"TRUE";
"B \NAC \NWC"2;
"S \NAC"
BN"6"103;
%"TAP"
"1","(-1250,3800)","2","mstr_standard","I132";
;
CDS_LIB"mstr_standard"
BODY_TYPE"PLUMBING"
HDL_TAP"TRUE";
"B \NAC \NWC"3;
"S \NAC"
BN"4"99;
%"DM-FCI-CONN76-8R-GP-U-01"
"1","(100,3475)","0","w_hdl","I134";
;
CDS_SEC"1"
CDS_LOCATION"J1F1"
LOCATION"J1F1"
NEW_PN"20.82092.076"
CONFIG"H22707-001"
VALUE"DM-FCI-CONN76-8R-GP-U-01"
PACK_TYPE"CONN-G4"
SEC"1"
SEC_TYPE"CONN-G4"
PART_NUMBER"ZZ.82092.07601"
CDS_LIB"w_hdl"
CDS_LMAN_SYM_OUTLINE"-475,1225,475,-1225";
"MB_SLOT_ID1"
$PN"G5"89;
"MB_SLOT_ID2"
$PN"H5"88;
"PCIE_PERST# \B"
$PN"I5"85;
"PMBUS_ALERT# \B"
$PN"A6"113;
"PCIE_CLK_100M_DN"
$PN"I4"53;
"J4"
$PN"J4"12;
"PCIE_CLK_100M_DP"
$PN"H4"75;
"GND14"
$PN"G4"12;
"FAN_PWM0"
$PN"F4"34;
"FAN_TACH1"
$PN"C4"28;
"MATED_IN# \B"
$PN"E4"76;
"FAN_TACH0"
$PN"D4"25;
"FAN_TACH2"
$PN"B4"26;
"FAN_TACH3"
$PN"A4"27;
"MB_ON# \B"
$PN"I3"47;
"COM_RX"
$PN"H3"57;
"GND11"
$PN"F3"12;
"COM_TX"
$PN"G3"48;
"PCIE_RX_DN7"
$PN"E3"49;
"GND4"
$PN"C3"12;
"PCIE_RX_DP7"
$PN"D3"46;
"PCIE_RX_DN6"
$PN"B3"50;
"PCIE_RX_DP6"
$PN"A3"51;
"J2"
$PN"J2"12;
"PCIE_RX_DN5"
$PN"I2"44;
"PCIE_RX_DN4"
$PN"F2"77;
"PCIE_RX_DP5"
$PN"H2"78;
"GND13"
$PN"G2"12;
"GND7"
$PN"D2"12;
"PCIE_RX_DP4"
$PN"E2"99;
"PCIE_RX_DN3"
$PN"C2"98;
"GND1"
$PN"A2"12;
"PCIE_RX_DP3"
$PN"B2"52;
"GND17"
$PN"I1"12;
"PCIE_RX_DN2"
$PN"H1"42;
"PCIE_RX_DP2"
$PN"G1"41;
"GND10"
$PN"F1"12;
"PCIE_RX_DP1"
$PN"D1"40;
"PCIE_RX_DN1"
$PN"E1"79;
"GND3"
$PN"C1"12;
"PCIE_RX_DN0"
$PN"B1"39;
"PCIE_RX_DP0"
$PN"A1"80;
"J8"
$PN"J8"15;
"PCIE_TX_DN2"
$PN"I8"32;
"PCIE_TX_DP2"
$PN"H8"33;
"GND16"
$PN"G8"15;
"PCIE_TX_DN1"
$PN"F8"94;
"GND9"
$PN"D8"15;
"PCIE_TX_DP1"
$PN"E8"81;
"PCIE_TX_DN0"
$PN"C8"86;
"GND2"
$PN"A8"15;
"PCIE_TX_DP0"
$PN"B8"93;
"PCIE_TX_DN5"
$PN"H7"82;
"GND18"
$PN"I7"15;
"GND12"
$PN"F7"15;
"PCIE_TX_DP5"
$PN"G7"92;
"PCIE_TX_DN4"
$PN"E7"96;
"GND6"
$PN"C7"15;
"PCIE_TX_DP4"
$PN"D7"83;
"PCIE_TX_DN3"
$PN"B7"97;
"PCIE_TX_DP3"
$PN"A7"108;
"PCIE_TX_DN7"
$PN"I6"87;
"J6"
$PN"J6"15;
"PCIE_TX_DP7"
$PN"H6"109;
"GND15"
$PN"G6"15;
"PCIE_TX_DN6"
$PN"F6"84;
"GND8"
$PN"D6"15;
"PCIE_TX_DP6"
$PN"E6"110;
"PMBUS_CLK"
$PN"C6"111;
"PMBUS_DATA"
$PN"B6"112;
"MNG_RX_DP"
$PN"D5"38;
"MNG_RX_DN"
$PN"E5"91;
"GND5"
$PN"C5"15;
"MNG_TX_DN"
$PN"B5"37;
"MNG_TX_DP"
$PN"A5"36;
"MB_SLOT_ID0"
$PN"F5"90;
%"GND"
"1","(-2200,1125)","0","mstr_symbols","I136";
;
HDL_POWER"GND"
BODY_TYPE"PLUMBING"
SIZE"1B"
VOLTAGE"0.0V"
CDS_LIB"mstr_symbols";
"A\NAC"7;
%"RES"
"1","(-2200,1300)","3","mstr_discrete","I137";
;
CDS_SEC"1"
CDS_LOCATION"R9T8"
PART_NUMBER"G21497-005"
PACK_TYPE"0402"
LOCATION"R9T8"
TOLERANCE"5%"
VALUE"0.0"
MATERIAL"CHIP"
WATTAGE"1/16W"
BOM_COST"PROC"
SEC_TYPE"0402"
SEC"1"
ROOM"PROC_SIDEBAND"
CDS_LIB"mstr_discrete";
"B"
$PN"2"7;
"A"
$PN"1"20;
%"P12V_PSU"
"1","(-2200,1975)","0","mstr_symbols","I21";
;
HDL_POWER"P12V_PSU"
BODY_TYPE"PLUMBING"
CDS_LIB"mstr_symbols"
BOM_COST"NT_BASE_VRD"
ROOM"P2V5_LAN_AUX_VR"
VOLTAGE"12.0";
"G\NAC"8;
%"RES"
"1","(-2225,2800)","0","mstr_discrete","I22";
;
PACK_TYPE"0402"
MATERIAL"CHIP"
TOLERANCE"5%"
WATTAGE"1/16W"
PART_NUMBER"G21497-005"
LOCATION"R1F8"
VALUE"0.0"
CDS_SEC"1"
CDS_LOCATION"R1F8"
CDS_LIB"mstr_discrete"
SEC_TYPE"0402"
SEC"1";
"B"
$PN"2"25;
"A"
$PN"1"56;
%"RES"
"1","(-1500,2700)","0","mstr_discrete","I26";
;
VALUE"0.0"
MATERIAL"CHIP"
TOLERANCE"5%"
WATTAGE"1/16W"
PACK_TYPE"0402"
LOCATION"R9T1"
PART_NUMBER"G21497-005"
CDS_SEC"1"
SEC"1"
SEC_TYPE"0402"
CDS_LIB"mstr_discrete"
CDS_LOCATION"R9T1";
"B"
$PN"2"34;
"A"
$PN"1"54;
%"RES"
"1","(-2225,2900)","0","mstr_discrete","I27";
;
VALUE"0.0"
WATTAGE"1/16W"
PART_NUMBER"G21497-005"
PACK_TYPE"0402"
TOLERANCE"5%"
LOCATION"R9R12"
MATERIAL"CHIP"
CDS_SEC"1"
CDS_LIB"mstr_discrete"
CDS_LOCATION"R9R12"
SEC"1"
SEC_TYPE"0402";
"B"
$PN"2"26;
"A"
$PN"1"60;
%"RES"
"1","(-2125,3100)","0","mstr_discrete","I28";
;
MATERIAL"EMPTY"
LOCATION"R9F63"
VALUE"0.0"
PART_NUMBER"G21497-005"
CDS_LOCATION"R9F63"
CDS_SEC"1"
TOLERANCE"5%"
WATTAGE"1/16W"
ROOM"UART_MUX"
SEC_TYPE"0402"
SEC"1"
CDS_LIB"mstr_discrete"
PACK_TYPE"0402";
"B"
$PN"2"57;
"A"
$PN"1"64;
%"RES"
"1","(-2175,3550)","0","mstr_discrete","I29";
;
TOLERANCE"5%"
VALUE"0.0"
PACK_TYPE"0402"
LOCATION"R9F64"
PART_NUMBER"G21497-005"
WATTAGE"1/16W"
MATERIAL"CHIP"
CDS_LOCATION"R9F64"
SEC_TYPE"0402"
ROOM"UART_MUX"
CDS_LIB"mstr_discrete"
SEC"1"
CDS_SEC"1";
"B"
$PN"2"57;
"A"
$PN"1"43;
%"RES"
"1","(-1750,3150)","0","mstr_discrete","I30";
;
TOLERANCE"5%"
PART_NUMBER"G21497-005"
MATERIAL"EMPTY"
LOCATION"R9F70"
VALUE"0.0"
WATTAGE"1/16W"
CDS_LOCATION"R9F70"
CDS_SEC"1"
CDS_LIB"mstr_discrete"
SEC"1"
SEC_TYPE"0402"
ROOM"UART_MUX"
PACK_TYPE"0402";
"B"
$PN"2"48;
"A"
$PN"1"58;
%"RES"
"1","(-1525,2850)","0","mstr_discrete","I31";
;
WATTAGE"1/16W"
MATERIAL"CHIP"
LOCATION"R9R10"
PACK_TYPE"0402"
TOLERANCE"5%"
PART_NUMBER"G21497-005"
VALUE"0.0"
CDS_SEC"1"
CDS_LIB"mstr_discrete"
CDS_LOCATION"R9R10"
SEC_TYPE"0402"
SEC"1";
"B"
$PN"2"28;
"A"
$PN"1"55;
%"RES"
"1","(-1525,2950)","0","mstr_discrete","I32";
;
WATTAGE"1/16W"
TOLERANCE"5%"
PACK_TYPE"0402"
MATERIAL"CHIP"
PART_NUMBER"G21497-005"
LOCATION"R9R9"
VALUE"0.0"
CDS_SEC"1"
CDS_LIB"mstr_discrete"
CDS_LOCATION"R9R9"
SEC_TYPE"0402"
SEC"1";
"B"
$PN"2"27;
"A"
$PN"1"66;
%"RES"
"1","(-1775,3600)","0","mstr_discrete","I33";
;
MATERIAL"CHIP"
PART_NUMBER"G21497-005"
WATTAGE"1/16W"
TOLERANCE"5%"
LOCATION"R9F67"
VALUE"0.0"
PACK_TYPE"0402"
CDS_LOCATION"R9F67"
ROOM"UART_MUX"
CDS_LIB"mstr_discrete"
$SEC"1"
CDS_SEC"1";
"B"
$PN"2"48;
"A"
$PN"1"59;
%"CAP_A"
"1","(-700,800)","0","dev_discrete","I34";
;
VALUE"0.1UF"
TOLERANCE"10%"
MATERIAL"X7R"
PART_NUMBER"A36096-030"
VOLTAGE"16V"
LOCATION"C8E1"
PACK_TYPE"0402V"
CDS_LOCATION"C8E1"
CDS_LIB"dev_discrete"
BOM_COST"IO_SLOT"
CDS_SEC"1"
SEC_TYPE"0402V"
SEC"1"
ROOM"IO_SLOT";
"B"
$PN"2"9;
"A"
$PN"1"10;
%"GND"
"1","(-700,500)","0","mstr_symbols","I35";
;
VOLTAGE"0.0V"
CDS_LIB"mstr_symbols"
SIZE"1B"
BODY_TYPE"PLUMBING"
HDL_POWER"GND";
"A\NAC"9;
%"P3V3_STBY"
"1","(-700,1100)","0","mstr_symbols","I36";
;
VOLTAGE"3.3V"
CDS_LIB"mstr_symbols"
SIZE"1B"
BODY_TYPE"PLUMBING"
HDL_POWER"P3V3_STBY";
"G\NAC"10;
%"DIODE"
"1","(-425,1550)","0","mstr_discrete","I37";
;
PART_NUMBER"H71799-001"
LOCATION"CR1F3"
VALUE"SDMK0340L"
MATERIAL"IC"
PACK_TYPE"SM"
CDS_SEC"1"
CDS_LIB"mstr_discrete"
CDS_LOCATION"CR1F3"
SEC"1"
BOM_COST"IO_SLOT"
SEC_TYPE"SM"
ROOM"IO_SLOT";
"C"
$PN"1"30;
"A"
$PN"2"29;
%"GND"
"1","(300,450)","0","mstr_symbols","I39";
;
ROOM"P2V5_LAN_AUX_VR"
BOM_COST"NT_BASE_VRD"
VOLTAGE"0"
CDS_LIB"mstr_symbols"
SIZE"1B"
BODY_TYPE"PLUMBING"
HDL_POWER"GND";
"A\NAC"11;
%"RES"
"2","(-2200,1750)","0","mstr_discrete","I4";
;
MATERIAL"CHIP"
WATTAGE"1/16W"
LOCATION"R9T9"
TOLERANCE"1%"
VALUE"4.75K"
PART_NUMBER"G21796-072"
PACK_TYPE"0402"
CDS_LOCATION"R9T9"
SEC"1"
SEC_TYPE"0402"
BOM_COST"IO_SLOT"
ROOM"IO_SLOT"
CDS_LIB"mstr_discrete"
CDS_SEC"1";
"A"
$PN"1"8;
"B"
$PN"2"20;
%"CAP"
"1","(300,625)","0","mstr_discrete","I40";
;
VOLTAGE"50V"
VALUE"470PF"
LOCATION"C2R6"
MATERIAL"EMPTY"
PART_NUMBER"A36096-049"
PACK_TYPE"0402LF"
TOLERANCE"10%"
CDS_SEC"1"
CDS_LOCATION"C2R6"
CDS_LIB"mstr_discrete"
SEC"1"
SEC_TYPE"0402LF"
ROOM"IO_SLOT";
"A"
$PN"1"35;
"B"
$PN"2"11;
%"NPN"
"1","(650,1550)","0","mstr_discrete","I42";
;
PACK_TYPE"SM"
MATERIAL"IC"
VALUE"MMBT3904"
PART_NUMBER"C52245-001"
LOCATION"Q9T1"
CDS_SEC"1"
CDS_LIB"mstr_discrete"
CDS_LOCATION"Q9T1"
SEC"1"
SEC_TYPE"SM"
ROOM"SB";
"C"
$PN"3"31;
"E"
$PN"2"13;
"B"
$PN"1"30;
%"GND"
"1","(-750,2400)","0","mstr_symbols","I43";
;
SIZE"1B"
VOLTAGE"0"
CDS_LIB"mstr_symbols"
ROOM"P2V5_LAN_AUX_VR"
BOM_COST"NT_BASE_VRD"
BODY_TYPE"PLUMBING"
HDL_POWER"GND";
"A\NAC"12;
%"TAP"
"1","(-1250,3300)","2","mstr_standard","I44";
;
CDS_LIB"mstr_standard"
BODY_TYPE"PLUMBING"
HDL_TAP"TRUE";
"B \NAC \NWC"3;
"S \NAC"
BN"7"46;
%"TAP"
"1","(-1000,3250)","2","mstr_standard","I45";
;
CDS_LIB"mstr_standard"
BODY_TYPE"PLUMBING"
HDL_TAP"TRUE";
"B \NAC \NWC"4;
"S \NAC"
BN"7"49;
%"TAP"
"1","(-1250,3400)","2","mstr_standard","I46";
;
CDS_LIB"mstr_standard"
BODY_TYPE"PLUMBING"
HDL_TAP"TRUE";
"B \NAC \NWC"3;
"S \NAC"
BN"6"50;
%"TAP"
"1","(-1250,3600)","2","mstr_standard","I47";
;
CDS_LIB"mstr_standard"
BODY_TYPE"PLUMBING"
HDL_TAP"TRUE";
"B \NAC \NWC"3;
"S \NAC"
BN"5"44;
%"TAP"
"1","(-1000,3450)","2","mstr_standard","I48";
;
CDS_LIB"mstr_standard"
BODY_TYPE"PLUMBING"
HDL_TAP"TRUE";
"B \NAC \NWC"4;
"S \NAC"
BN"6"51;
%"TAP"
"1","(-1000,3650)","2","mstr_standard","I49";
;
CDS_LIB"mstr_standard"
BODY_TYPE"PLUMBING"
HDL_TAP"TRUE";
"B \NAC \NWC"4;
"S \NAC"
BN"5"78;
%"DIODE"
"1","(-1550,1550)","0","mstr_discrete","I5";
;
MATERIAL"IC"
PART_NUMBER"H71799-001"
VALUE"SDMK0340L"
LOCATION"CR1F4"
PACK_TYPE"SM"
SEC"1"
SEC_TYPE"SM"
BOM_COST"IO_SLOT"
ROOM"IO_SLOT"
CDS_LIB"mstr_discrete"
CDS_LOCATION"CR1F4"
CDS_SEC"1";
"C"
$PN"1"29;
"A"
$PN"2"20;
%"TAP"
"1","(-1000,3750)","2","mstr_standard","I50";
;
CDS_LIB"mstr_standard"
BODY_TYPE"PLUMBING"
HDL_TAP"TRUE";
"B \NAC \NWC"4;
"S \NAC"
BN"4"77;
%"TAP"
"1","(-1250,3950)","2","mstr_standard","I52";
;
CDS_LIB"mstr_standard"
BODY_TYPE"PLUMBING"
HDL_TAP"TRUE";
"B \NAC \NWC"3;
"S \NAC"
BN"3"52;
%"TAP"
"1","(-1250,4150)","2","mstr_standard","I53";
;
CDS_LIB"mstr_standard"
BODY_TYPE"PLUMBING"
HDL_TAP"TRUE";
"B \NAC \NWC"3;
"S \NAC"
BN"2"42;
%"TAP"
"1","(-1250,4350)","2","mstr_standard","I54";
;
CDS_LIB"mstr_standard"
BODY_TYPE"PLUMBING"
HDL_TAP"TRUE";
"B \NAC \NWC"3;
"S \NAC"
BN"1"40;
%"TAP"
"1","(-1000,3900)","2","mstr_standard","I55";
;
CDS_LIB"mstr_standard"
BODY_TYPE"PLUMBING"
HDL_TAP"TRUE";
"B \NAC \NWC"4;
"S \NAC"
BN"3"98;
%"TAP"
"1","(-1000,4200)","2","mstr_standard","I56";
;
CDS_LIB"mstr_standard"
BODY_TYPE"PLUMBING"
HDL_TAP"TRUE";
"B \NAC \NWC"4;
"S \NAC"
BN"2"41;
%"TAP"
"1","(-1000,4300)","2","mstr_standard","I57";
;
CDS_LIB"mstr_standard"
BODY_TYPE"PLUMBING"
HDL_TAP"TRUE";
"B \NAC \NWC"4;
"S \NAC"
BN"1"79;
%"TAP"
"1","(-1250,4500)","2","mstr_standard","I58";
;
CDS_LIB"mstr_standard"
BODY_TYPE"PLUMBING"
HDL_TAP"TRUE";
"B \NAC \NWC"3;
"S \NAC"
BN"0"80;
%"TAP"
"1","(-1000,4450)","2","mstr_standard","I59";
;
CDS_LIB"mstr_standard"
BODY_TYPE"PLUMBING"
HDL_TAP"TRUE";
"B \NAC \NWC"4;
"S \NAC"
BN"0"39;
%"TTL08"
"1","(850,825)","0","mstr_ttl","I60";
;
MATERIAL"IC"
LOCATION"U8E1"
VALUE"74LVC08A"
POWER_GROUP"VCC=P3V3_STBY;GND=GND;TH=GND"
PART_NUMBER"D90404-001"
CDS_SEC"2"
CDS_LIB"mstr_ttl"
SEC"2"
BOM_COST"FAST_PROCHOT"
SEC_TYPE"QFN15"
CDS_LOCATION"U8E1"
ROOM"FAST_PROCHOT"
PACK_TYPE"QFN15";
"A <SIZE-1..0>"
$PN"9"35;
"B <SIZE-1..0>"
$PN"10"105;
"Y <SIZE-1..0>"
$PN"8"61;
%"GND"
"1","(700,1275)","0","mstr_symbols","I61";
;
BOM_COST"NT_BASE_VRD"
ROOM"P2V5_LAN_AUX_VR"
SIZE"1B"
VOLTAGE"0"
CDS_LIB"mstr_symbols"
BODY_TYPE"PLUMBING"
HDL_POWER"GND";
"A\NAC"13;
%"GND"
"1","(1150,1250)","0","mstr_symbols","I62";
;
BOM_COST"NT_BASE_VRD"
ROOM"P2V5_LAN_AUX_VR"
SIZE"1B"
VOLTAGE"0"
CDS_LIB"mstr_symbols"
BODY_TYPE"PLUMBING"
HDL_POWER"GND";
"A\NAC"14;
%"RES"
"1","(1650,825)","0","mstr_discrete","I63";
;
WATTAGE"1/16W"
LOCATION"R8E5"
VALUE"33.2"
TOLERANCE"1%"
MATERIAL"CHIP"
PACK_TYPE"0402"
PART_NUMBER"G21796-074"
CDS_SEC"1"
ROOM"IO_SLOT"
SEC_TYPE"0402"
SEC"1"
CDS_LOCATION"R8E5"
CDS_LIB"mstr_discrete";
"B"
$PN"2"106;
"A"
$PN"1"61;
%"RES"
"2","(1150,1550)","0","mstr_discrete","I64";
;
WATTAGE"1/16W"
TOLERANCE"1%"
PART_NUMBER"G21796-161"
MATERIAL"CHIP"
PACK_TYPE"0402"
LOCATION"R9T3"
VALUE"6.19K"
BOM_COST"IO_SLOT"
SEC"1"
SEC_TYPE"0402"
ROOM"IO_SLOT"
CDS_LOCATION"R9T3"
CDS_LIB"mstr_discrete"
CDS_SEC"1";
"A"
$PN"1"31;
"B"
$PN"2"14;
%"GND"
"1","(900,2400)","0","mstr_symbols","I67";
;
CDS_LIB"mstr_symbols"
SIZE"1B"
VOLTAGE"0"
BOM_COST"NT_BASE_VRD"
ROOM"P2V5_LAN_AUX_VR"
BODY_TYPE"PLUMBING"
HDL_POWER"GND";
"A\NAC"15;
%"RES"
"2","(1050,1900)","2","mstr_discrete","I68";
;
LOCATION"R9T6"
PACK_TYPE"0402"
TOLERANCE"1%"
WATTAGE"1/16W"
MATERIAL"CHIP"
PART_NUMBER"G21796-107"
VALUE"15.0K"
CDS_SEC"1"
CDS_LIB"mstr_discrete"
CDS_LOCATION"R9T6"
ROOM"IO_SLOT"
SEC_TYPE"0402"
BOM_COST"IO_SLOT"
SEC"1";
"A"
$PN"1"16;
"B"
$PN"2"31;
%"P12V_PSU"
"1","(1050,2100)","0","mstr_symbols","I69";
;
VOLTAGE"12.0"
ROOM"P2V5_LAN_AUX_VR"
BOM_COST"NT_BASE_VRD"
CDS_LIB"mstr_symbols"
BODY_TYPE"PLUMBING"
HDL_POWER"P12V_PSU";
"G\NAC"16;
%"CAP"
"2","(1775,2550)","0","mstr_discrete","I70";
;
MATERIAL"X7R"
TOLERANCE"10%"
LOCATION"C1F14"
PACK_TYPE"0402"
VOLTAGE"16V"
PART_NUMBER"A36096-155"
VALUE"0.22UF"
CDS_SEC"1"
CDS_LIB"mstr_discrete"
CDS_LOCATION"C1F14"
BOM_COST"IO_SLOT"
ROOM"IO_SLOT"
SEC_TYPE"0402"
SEC"1";
"A"
$PN"1"32;
"B"
$PN"2"45;
%"CAP"
"2","(1775,2700)","0","mstr_discrete","I71";
;
PACK_TYPE"0402"
VOLTAGE"16V"
PART_NUMBER"A36096-155"
LOCATION"C1F17"
MATERIAL"X7R"
TOLERANCE"10%"
VALUE"0.22UF"
CDS_SEC"1"
CDS_LIB"mstr_discrete"
CDS_LOCATION"C1F17"
ROOM"IO_SLOT"
SEC"1"
SEC_TYPE"0402"
BOM_COST"IO_SLOT";
"A"
$PN"1"94;
"B"
$PN"2"74;
%"CAP"
"2","(1775,2850)","0","mstr_discrete","I72";
;
PACK_TYPE"0402"
TOLERANCE"10%"
MATERIAL"X7R"
VALUE"0.22UF"
PART_NUMBER"A36096-155"
LOCATION"C1F18"
VOLTAGE"16V"
CDS_SEC"1"
BOM_COST"IO_SLOT"
CDS_LIB"mstr_discrete"
CDS_LOCATION"C1F18"
ROOM"IO_SLOT"
SEC"1"
SEC_TYPE"0402";
"A"
$PN"1"86;
"B"
$PN"2"73;
%"CAP"
"2","(1825,3100)","0","mstr_discrete","I73";
;
PACK_TYPE"0402"
MATERIAL"X7R"
LOCATION"C1F8"
PART_NUMBER"A36096-155"
TOLERANCE"10%"
VALUE"0.22UF"
VOLTAGE"16V"
CDS_SEC"1"
CDS_LOCATION"C1F8"
BOM_COST"IO_SLOT"
CDS_LIB"mstr_discrete"
ROOM"IO_SLOT"
SEC_TYPE"0402"
SEC"1";
"A"
$PN"1"82;
"B"
$PN"2"72;
%"CAP"
"2","(1825,3250)","0","mstr_discrete","I74";
;
VOLTAGE"16V"
LOCATION"C1F11"
TOLERANCE"10%"
PART_NUMBER"A36096-155"
VALUE"0.22UF"
MATERIAL"X7R"
PACK_TYPE"0402"
CDS_SEC"1"
CDS_LIB"mstr_discrete"
CDS_LOCATION"C1F11"
SEC"1"
BOM_COST"IO_SLOT"
SEC_TYPE"0402"
ROOM"IO_SLOT";
"A"
$PN"1"96;
"B"
$PN"2"71;
%"CAP"
"2","(1825,3400)","0","mstr_discrete","I75";
;
TOLERANCE"10%"
PACK_TYPE"0402"
VALUE"0.22UF"
LOCATION"C1F12"
MATERIAL"X7R"
VOLTAGE"16V"
PART_NUMBER"A36096-155"
CDS_SEC"1"
ROOM"IO_SLOT"
SEC_TYPE"0402"
SEC"1"
BOM_COST"IO_SLOT"
CDS_LIB"mstr_discrete"
CDS_LOCATION"C1F12";
"A"
$PN"1"97;
"B"
$PN"2"107;
%"CAP"
"2","(1825,3600)","0","mstr_discrete","I76";
;
VOLTAGE"16V"
MATERIAL"X7R"
TOLERANCE"10%"
LOCATION"C1F3"
PART_NUMBER"A36096-155"
VALUE"0.22UF"
PACK_TYPE"0402"
CDS_SEC"1"
CDS_LOCATION"C1F3"
BOM_COST"IO_SLOT"
CDS_LIB"mstr_discrete"
ROOM"IO_SLOT"
SEC_TYPE"0402"
SEC"1";
"A"
$PN"1"87;
"B"
$PN"2"101;
%"CAP"
"2","(1825,3750)","0","mstr_discrete","I77";
;
VOLTAGE"16V"
PACK_TYPE"0402"
MATERIAL"X7R"
PART_NUMBER"A36096-155"
LOCATION"C1F5"
TOLERANCE"10%"
VALUE"0.22UF"
CDS_SEC"1"
CDS_LIB"mstr_discrete"
ROOM"IO_SLOT"
BOM_COST"IO_SLOT"
SEC_TYPE"0402"
SEC"1"
CDS_LOCATION"C1F5";
"A"
$PN"1"84;
"B"
$PN"2"104;
%"CAP"
"2","(2275,2600)","0","mstr_discrete","I78";
;
VALUE"0.22UF"
LOCATION"C1F15"
VOLTAGE"16V"
MATERIAL"X7R"
TOLERANCE"10%"
PACK_TYPE"0402"
PART_NUMBER"A36096-155"
CDS_SEC"1"
CDS_LOCATION"C1F15"
BOM_COST"IO_SLOT"
CDS_LIB"mstr_discrete"
ROOM"IO_SLOT"
SEC"1"
SEC_TYPE"0402";
"A"
$PN"1"33;
"B"
$PN"2"69;
%"CAP"
"2","(2275,2750)","0","mstr_discrete","I79";
;
PART_NUMBER"A36096-155"
VALUE"0.22UF"
LOCATION"C1F16"
TOLERANCE"10%"
PACK_TYPE"0402"
MATERIAL"X7R"
VOLTAGE"16V"
CDS_SEC"1"
CDS_LIB"mstr_discrete"
CDS_LOCATION"C1F16"
SEC"1"
SEC_TYPE"0402"
BOM_COST"IO_SLOT"
ROOM"IO_SLOT";
"A"
$PN"1"81;
"B"
$PN"2"70;
%"RES"
"1","(2650,2050)","0","mstr_discrete","I80";
;
PACK_TYPE"0402"
LOCATION"R7D9"
WATTAGE"1/16W"
VALUE"2.26K"
TOLERANCE"1.0%"
MATERIAL"CHIP"
PART_NUMBER"G21796-311"
CDS_SEC"1"
CDS_LOCATION"R7D9"
SEC"1"
SEC_TYPE"0402"
ROOM"IO_SLOT"
CDS_LIB"mstr_discrete";
"B"
$PN"2"24;
"A"
$PN"1"17;
%"RES"
"1","(2650,1875)","0","mstr_discrete","I81";
;
VALUE"2.26K"
PACK_TYPE"0402"
MATERIAL"CHIP"
PART_NUMBER"G21796-311"
LOCATION"R3P61"
TOLERANCE"1.0%"
WATTAGE"1/16W"
CDS_SEC"1"
CDS_LOCATION"R3P61"
ROOM"IO_SLOT"
SEC_TYPE"0402"
SEC"1"
CDS_LIB"mstr_discrete";
"B"
$PN"2"63;
"A"
$PN"1"17;
%"RES"
"1","(2650,2225)","0","mstr_discrete","I82";
;
PACK_TYPE"0402"
WATTAGE"1/16W"
VALUE"2.26K"
MATERIAL"CHIP"
PART_NUMBER"G21796-311"
LOCATION"R7D5"
TOLERANCE"1.0%"
CDS_SEC"1"
CDS_LOCATION"R7D5"
SEC"1"
SEC_TYPE"0402"
ROOM"IO_SLOT"
CDS_LIB"mstr_discrete";
"B"
$PN"2"65;
"A"
$PN"1"17;
%"P3V3_STBY"
"1","(2325,2375)","0","mstr_symbols","I83";
;
CDS_LIB"mstr_symbols"
SIZE"1B"
VOLTAGE"3.3V"
BODY_TYPE"PLUMBING"
HDL_POWER"P3V3_STBY";
"G\NAC"17;
%"TAP"
"6","(2925,2700)","2","mstr_standard","I84";
;
CDS_LIB"mstr_standard"
BODY_TYPE"PLUMBING"
HDL_TAP"TRUE";
"B \NAC \NWC"1;
"S \NAC"
BN"1"74;
%"TAP"
"6","(2925,2550)","2","mstr_standard","I85";
;
CDS_LIB"mstr_standard"
BODY_TYPE"PLUMBING"
HDL_TAP"TRUE";
"B \NAC \NWC"1;
"S \NAC"
BN"2"45;
%"CAP"
"2","(2275,2900)","0","mstr_discrete","I86";
;
LOCATION"C1F20"
MATERIAL"X7R"
TOLERANCE"10%"
PACK_TYPE"0402"
VOLTAGE"16V"
VALUE"0.22UF"
PART_NUMBER"A36096-155"
CDS_SEC"1"
CDS_LOCATION"C1F20"
CDS_LIB"mstr_discrete"
BOM_COST"IO_SLOT"
ROOM"IO_SLOT"
SEC_TYPE"0402"
SEC"1";
"A"
$PN"1"93;
"B"
$PN"2"95;
%"CAP"
"2","(2275,3300)","0","mstr_discrete","I87";
;
LOCATION"C1F10"
MATERIAL"X7R"
TOLERANCE"10%"
VALUE"0.22UF"
VOLTAGE"16V"
PACK_TYPE"0402"
PART_NUMBER"A36096-155"
CDS_SEC"1"
CDS_LIB"mstr_discrete"
CDS_LOCATION"C1F10"
BOM_COST"IO_SLOT"
ROOM"IO_SLOT"
SEC"1"
SEC_TYPE"0402";
"A"
$PN"1"83;
"B"
$PN"2"67;
%"CAP"
"2","(2275,3150)","0","mstr_discrete","I88";
;
VOLTAGE"16V"
PART_NUMBER"A36096-155"
LOCATION"C1F6"
VALUE"0.22UF"
MATERIAL"X7R"
PACK_TYPE"0402"
TOLERANCE"10%"
CDS_SEC"1"
CDS_LIB"mstr_discrete"
CDS_LOCATION"C1F6"
BOM_COST"IO_SLOT"
ROOM"IO_SLOT"
SEC_TYPE"0402"
SEC"1";
"A"
$PN"1"92;
"B"
$PN"2"68;
%"CAP"
"2","(2250,3450)","0","mstr_discrete","I89";
;
LOCATION"C1F13"
VOLTAGE"16V"
MATERIAL"X7R"
VALUE"0.22UF"
TOLERANCE"10%"
PACK_TYPE"0402"
PART_NUMBER"A36096-155"
CDS_SEC"1"
CDS_LIB"mstr_discrete"
CDS_LOCATION"C1F13"
ROOM"IO_SLOT"
BOM_COST"IO_SLOT"
SEC_TYPE"0402"
SEC"1";
"A"
$PN"1"108;
"B"
$PN"2"100;
%"CAP"
"2","(2250,3650)","0","mstr_discrete","I90";
;
PART_NUMBER"A36096-155"
VOLTAGE"16V"
MATERIAL"X7R"
LOCATION"C1F2"
VALUE"0.22UF"
PACK_TYPE"0402"
TOLERANCE"10%"
CDS_SEC"1"
CDS_LIB"mstr_discrete"
CDS_LOCATION"C1F2"
BOM_COST"IO_SLOT"
ROOM"IO_SLOT"
SEC_TYPE"0402"
SEC"1";
"A"
$PN"1"109;
"B"
$PN"2"102;
%"CAP"
"2","(2250,3800)","0","mstr_discrete","I91";
;
LOCATION"C1F4"
VOLTAGE"16V"
PACK_TYPE"0402"
PART_NUMBER"A36096-155"
TOLERANCE"10%"
MATERIAL"X7R"
VALUE"0.22UF"
CDS_SEC"1"
CDS_LIB"mstr_discrete"
CDS_LOCATION"C1F4"
BOM_COST"IO_SLOT"
ROOM"IO_SLOT"
SEC_TYPE"0402"
SEC"1";
"A"
$PN"1"110;
"B"
$PN"2"103;
%"TAP"
"6","(2925,3150)","2","mstr_standard","I92";
;
CDS_LIB"mstr_standard"
BODY_TYPE"PLUMBING"
HDL_TAP"TRUE";
"B \NAC \NWC"1;
"S \NAC"
BN"5"68;
%"TAP"
"6","(2925,3250)","2","mstr_standard","I93";
;
CDS_LIB"mstr_standard"
BODY_TYPE"PLUMBING"
HDL_TAP"TRUE";
"B \NAC \NWC"1;
"S \NAC"
BN"4"71;
%"TAP"
"6","(2925,2850)","2","mstr_standard","I94";
;
CDS_LIB"mstr_standard"
BODY_TYPE"PLUMBING"
HDL_TAP"TRUE";
"B \NAC \NWC"1;
"S \NAC"
BN"0"73;
%"TAP"
"6","(2925,3650)","2","mstr_standard","I95";
;
CDS_LIB"mstr_standard"
BODY_TYPE"PLUMBING"
HDL_TAP"TRUE";
"B \NAC \NWC"1;
"S \NAC"
BN"7"102;
%"TAP"
"6","(2925,3750)","2","mstr_standard","I96";
;
CDS_LIB"mstr_standard"
BODY_TYPE"PLUMBING"
HDL_TAP"TRUE";
"B \NAC \NWC"1;
"S \NAC"
BN"6"104;
%"TAP"
"6","(2925,3400)","2","mstr_standard","I97";
;
CDS_LIB"mstr_standard"
BODY_TYPE"PLUMBING"
HDL_TAP"TRUE";
"B \NAC \NWC"1;
"S \NAC"
BN"3"107;
END.
